# T6G (Grand Teton) — schematic netlist excerpt (pin names and nets, part order shuffled) for the footprints in the layout excerpt that follows; sources: Cadence DE-HDL packaged netlist, KiCad conversion of 04192023_DAF0TMB3IC0_F0TG_MB_C_brd_V02_OCP.brd

C6751  Q_CAP_DIFFBUS  DIFF BUS_0.22UF 6.3V 20% X6S  pkg C0201  page 352 : \1\ = P5E_CPU1_P3_TX_BUF_C_DP<13> ; \2\ = P5E_CPU1_P3_TX_BUF_DP<13>
R6784  Q_RES  0 5% CHIP  pkg 0402LF  page 151 : A = SMB_MUX_RT_R1_SCL ; B = SMB_SML1_PMBUS_HSC_SCL
PR174  Q_RES  0 5% CHIP  pkg 0402LF  page 210 : A = VSENSE_PVDDCR_SOC_P1_DP ; B = VSENSE_PVDDCR_SOC_P1_VSEN1

(kicad_pcb
	(version 20260206)
	(generator "pcbnew")
	(generator_version "10.0")
	(general
		(thickness 1.6)
		(legacy_teardrops no)
	)
	(paper "A4")
	(title_block
		(title "04192023_DAF0TMB3IC0_F0TG_MB_C_brd_V02_OCP.brd")
		(comment 1 "Grand Teton / footprints 7523-7525 of 8354")
	)
	(layers
		(0 "F.Cu" signal "TOP")
		(4 "In1.Cu" signal "GND")
		(6 "In2.Cu" signal "IN1")
		(8 "In3.Cu" signal "GND1")
		(10 "In4.Cu" signal "IN2")
		(12 "In5.Cu" signal "GND2")
		(14 "In6.Cu" signal "IN3")
		(16 "In7.Cu" signal "GND3")
		(18 "In8.Cu" signal "VCC")
		(20 "In9.Cu" signal "VCC1")
		(22 "In10.Cu" signal "GND4")
		(24 "In11.Cu" signal "IN4")
		(26 "In12.Cu" signal "GND5")
		(28 "In13.Cu" signal "IN5")
		(30 "In14.Cu" signal "GND6")
		(32 "In15.Cu" signal "IN6")
		(34 "In16.Cu" signal "GND7")
		(2 "B.Cu" signal "BOTTOM")
		(9 "F.Adhes" user "F.Adhesive")
		(11 "B.Adhes" user "B.Adhesive")
		(13 "F.Paste" user "Package Geometry/Pastemask Top")
		(15 "B.Paste" user "Package Geometry/Pastemask Bottom")
		(5 "F.SilkS" user "Ref Des/Silkscreen Top")
		(7 "B.SilkS" user "Ref Des/Silkscreen Bottom")
		(1 "F.Mask" user "Board Geometry/Soldermask Top")
		(3 "B.Mask" user "Board Geometry/Soldermask Bottom")
		(17 "Dwgs.User" user "User.Drawings")
		(19 "Cmts.User" user "User.Comments")
		(21 "Eco1.User" user "User.Eco1")
		(23 "Eco2.User" user "User.Eco2")
		(25 "Edge.Cuts" user "Board Geometry/Outline")
		(27 "Margin" user)
		(31 "F.CrtYd" user "Package Geometry/Place Bound Top")
		(29 "B.CrtYd" user "Package Geometry/Place Bound Bottom")
		(35 "F.Fab" user "Ref Des/Assembly Top")
		(33 "B.Fab" user "Ref Des/Assembly Bottom")
	)
	(footprint ""
		(layer "B.Cu")
		(at 157.136846 -408.517344 90)
		(property "Reference" "C6751"
			(at 0 0 90)
			(layer "B.SilkS")
			(hide yes)
			(effects
				(font
					(size 1.27 1.27)
				)
				(justify mirror)
			)
		)
		(property "Value" ""
			(at 0 0 90)
			(layer "B.Fab")
			(effects
				(font
					(size 1.27 1.27)
				)
				(justify mirror)
			)
		)
		(duplicate_pad_numbers_are_jumpers no)
		(fp_line
			(start 0.299974 -0.150114)
			(end -0.299974 -0.150114)
			(stroke
				(width 0.1)
				(type default)
			)
			(layer "B.Fab")
		)
		(fp_line
			(start -0.299974 -0.150114)
			(end -0.299974 0.150114)
			(stroke
				(width 0.1)
				(type default)
			)
			(layer "B.Fab")
		)
		(fp_line
			(start 0.299974 0.150114)
			(end 0.299974 -0.150114)
			(stroke
				(width 0.1)
				(type default)
			)
			(layer "B.Fab")
		)
		(fp_line
			(start -0.299974 0.150114)
			(end 0.299974 0.150114)
			(stroke
				(width 0.1)
				(type default)
			)
			(layer "B.Fab")
		)
		(pad "1" smd rect
			(at 0.2667 0 270)
			(size 0.3048 0.381)
			(layers "B.Cu" "B.Mask" "B.Paste")
			(net "P5E_CPU1_P3_TX_BUF_C_DP<13>")
		)
		(pad "2" smd rect
			(at -0.2667 0 270)
			(size 0.3048 0.381)
			(layers "B.Cu" "B.Mask" "B.Paste")
			(net "P5E_CPU1_P3_TX_BUF_DP<13>")
		)
	)
	(footprint ""
		(layer "B.Cu")
		(at 233.68 -331.724 180)
		(property "Reference" "R6784"
			(at 0 0 0)
			(layer "B.SilkS")
			(hide yes)
			(effects
				(font
					(size 1.27 1.27)
				)
				(justify mirror)
			)
		)
		(property "Value" ""
			(at 0 0 0)
			(layer "B.Fab")
			(effects
				(font
					(size 1.27 1.27)
				)
				(justify mirror)
			)
		)
		(duplicate_pad_numbers_are_jumpers no)
		(fp_line
			(start 0.7874 0.4064)
			(end 0.7874 -0.4064)
			(stroke
				(width 0.1524)
				(type default)
			)
			(layer "B.SilkS")
		)
		(fp_line
			(start 0.7874 -0.4064)
			(end -0.7874 -0.4064)
			(stroke
				(width 0.1524)
				(type default)
			)
			(layer "B.SilkS")
		)
		(fp_line
			(start -0.7874 0.4064)
			(end 0.7874 0.4064)
			(stroke
				(width 0.1524)
				(type default)
			)
			(layer "B.SilkS")
		)
		(fp_line
			(start -0.7874 -0.4064)
			(end -0.7874 0.4064)
			(stroke
				(width 0.1524)
				(type default)
			)
			(layer "B.SilkS")
		)
		(fp_line
			(start 0.67945 0.3048)
			(end 0.67945 -0.305054)
			(stroke
				(width 0.1)
				(type default)
			)
			(layer "B.Fab")
		)
		(fp_line
			(start 0.67945 -0.305054)
			(end 0.12065 -0.305054)
			(stroke
				(width 0.1)
				(type default)
			)
			(layer "B.Fab")
		)
		(fp_line
			(start 0.12065 0.3048)
			(end 0.67945 0.3048)
			(stroke
				(width 0.1)
				(type default)
			)
			(layer "B.Fab")
		)
		(fp_line
			(start 0.12065 0.2794)
			(end 0.12065 0.3048)
			(stroke
				(width 0.1)
				(type default)
			)
			(layer "B.Fab")
		)
		(fp_line
			(start 0.12065 -0.2794)
			(end -0.12065 -0.2794)
			(stroke
				(width 0.1)
				(type default)
			)
			(layer "B.Fab")
		)
		(fp_line
			(start 0.12065 -0.305054)
			(end 0.12065 -0.2794)
			(stroke
				(width 0.1)
				(type default)
			)
			(layer "B.Fab")
		)
		(fp_line
			(start -0.120396 0.3048)
			(end -0.120396 0.2794)
			(stroke
				(width 0.1)
				(type default)
			)
			(layer "B.Fab")
		)
		(fp_line
			(start -0.120396 0.2794)
			(end 0.12065 0.2794)
			(stroke
				(width 0.1)
				(type default)
			)
			(layer "B.Fab")
		)
		(fp_line
			(start -0.12065 -0.2794)
			(end -0.12065 -0.3048)
			(stroke
				(width 0.1)
				(type default)
			)
			(layer "B.Fab")
		)
		(fp_line
			(start -0.12065 -0.3048)
			(end -0.67945 -0.3048)
			(stroke
				(width 0.1)
				(type default)
			)
			(layer "B.Fab")
		)
		(fp_line
			(start -0.67945 0.3048)
			(end -0.120396 0.3048)
			(stroke
				(width 0.1)
				(type default)
			)
			(layer "B.Fab")
		)
		(fp_line
			(start -0.67945 -0.3048)
			(end -0.67945 0.3048)
			(stroke
				(width 0.1)
				(type default)
			)
			(layer "B.Fab")
		)
		(pad "1" smd circle
			(at 0.40005 0)
			(size 0 0)
			(layers "B.Cu" "B.Mask" "B.Paste")
			(net "SMB_MUX_RT_R1_SCL")
		)
		(pad "2" smd circle
			(at -0.40005 0)
			(size 0 0)
			(layers "B.Cu" "B.Mask" "B.Paste")
			(net "SMB_SML1_PMBUS_HSC_SCL")
		)
	)
	(footprint ""
		(layer "B.Cu")
		(at 102.401878 -146.66341)
		(property "Reference" "PR174"
			(at 0 0 0)
			(layer "B.SilkS")
			(hide yes)
			(effects
				(font
					(size 1.27 1.27)
				)
				(justify mirror)
			)
		)
		(property "Value" ""
			(at 0 0 0)
			(layer "B.Fab")
			(effects
				(font
					(size 1.27 1.27)
				)
				(justify mirror)
			)
		)
		(duplicate_pad_numbers_are_jumpers no)
		(fp_line
			(start -0.7874 -0.4064)
			(end -0.7874 0.4064)
			(stroke
				(width 0.1524)
				(type default)
			)
			(layer "B.SilkS")
		)
		(fp_line
			(start -0.7874 0.4064)
			(end 0.7874 0.4064)
			(stroke
				(width 0.1524)
				(type default)
			)
			(layer "B.SilkS")
		)
		(fp_line
			(start 0.7874 -0.4064)
			(end -0.7874 -0.4064)
			(stroke
				(width 0.1524)
				(type default)
			)
			(layer "B.SilkS")
		)
		(fp_line
			(start 0.7874 0.4064)
			(end 0.7874 -0.4064)
			(stroke
				(width 0.1524)
				(type default)
			)
			(layer "B.SilkS")
		)
		(fp_line
			(start -0.67945 -0.3048)
			(end -0.67945 0.3048)
			(stroke
				(width 0.1)
				(type default)
			)
			(layer "B.Fab")
		)
		(fp_line
			(start -0.67945 0.3048)
			(end -0.120396 0.3048)
			(stroke
				(width 0.1)
				(type default)
			)
			(layer "B.Fab")
		)
		(fp_line
			(start -0.12065 -0.3048)
			(end -0.67945 -0.3048)
			(stroke
				(width 0.1)
				(type default)
			)
			(layer "B.Fab")
		)
		(fp_line
			(start -0.12065 -0.2794)
			(end -0.12065 -0.3048)
			(stroke
				(width 0.1)
				(type default)
			)
			(layer "B.Fab")
		)
		(fp_line
			(start -0.120396 0.2794)
			(end 0.12065 0.2794)
			(stroke
				(width 0.1)
				(type default)
			)
			(layer "B.Fab")
		)
		(fp_line
			(start -0.120396 0.3048)
			(end -0.120396 0.2794)
			(stroke
				(width 0.1)
				(type default)
			)
			(layer "B.Fab")
		)
		(fp_line
			(start 0.12065 -0.305054)
			(end 0.12065 -0.2794)
			(stroke
				(width 0.1)
				(type default)
			)
			(layer "B.Fab")
		)
		(fp_line
			(start 0.12065 -0.2794)
			(end -0.12065 -0.2794)
			(stroke
				(width 0.1)
				(type default)
			)
			(layer "B.Fab")
		)
		(fp_line
			(start 0.12065 0.2794)
			(end 0.12065 0.3048)
			(stroke
				(width 0.1)
				(type default)
			)
			(layer "B.Fab")
		)
		(fp_line
			(start 0.12065 0.3048)
			(end 0.67945 0.3048)
			(stroke
				(width 0.1)
				(type default)
			)
			(layer "B.Fab")
		)
		(fp_line
			(start 0.67945 -0.305054)
			(end 0.12065 -0.305054)
			(stroke
				(width 0.1)
				(type default)
			)
			(layer "B.Fab")
		)
		(fp_line
			(start 0.67945 0.3048)
			(end 0.67945 -0.305054)
			(stroke
				(width 0.1)
				(type default)
			)
			(layer "B.Fab")
		)
		(pad "1" smd circle
			(at 0.40005 0 180)
			(size 0 0)
			(layers "B.Cu" "B.Mask" "B.Paste")
			(net "VSENSE_PVDDCR_SOC_P1_DP")
		)
		(pad "2" smd circle
			(at -0.40005 0 180)
			(size 0 0)
			(layers "B.Cu" "B.Mask" "B.Paste")
			(net "VSENSE_PVDDCR_SOC_P1_VSEN1")
		)
	)
)
